# BASEBOARD_FAB2 (Tioga Pass) — schematic netlist excerpt (pin names and nets, part order shuffled) for the footprints in the layout excerpt that follows; sources: Cadence DE-HDL packaged netlist, KiCad conversion of Wiwynn_Tioga_Pass_MB.brd

CT43  CAP  1000PF 50V 10% X7R  pkg 0402LF  page 219 : A = A_TSENSE_PVDDQ_DEF ; B = GND
R3P25  RES  1.00K 1% CHIP  pkg 0402  page 211 : A = P3V3_STBY ; B = PWRGD_PVCCIO_CPU0_R
R4P17  RES  150.0 1% CHIP  pkg 0402  page 152 : A = H_CPU0_MEMABC_MEMHOT_G_N ; B = PVCCIO_CPU0

(kicad_pcb
	(version 20260206)
	(generator "pcbnew")
	(generator_version "10.0")
	(general
		(thickness 1.6)
		(legacy_teardrops no)
	)
	(paper "A4")
	(title_block
		(title "Wiwynn_Tioga_Pass_MB.brd")
		(comment 1 "Tioga Pass / footprints 3887-3889 of 4770")
	)
	(layers
		(0 "F.Cu" signal "TOP")
		(4 "In1.Cu" signal "L2GND")
		(6 "In2.Cu" signal "L3")
		(8 "In3.Cu" signal "L4GND")
		(10 "In4.Cu" signal "L5")
		(12 "In5.Cu" signal "L6GND")
		(14 "In6.Cu" signal "L7VCC")
		(16 "In7.Cu" signal "L8VCC")
		(18 "In8.Cu" signal "L9GND")
		(20 "In9.Cu" signal "L10")
		(22 "In10.Cu" signal "L11GND")
		(24 "In11.Cu" signal "L12")
		(26 "In12.Cu" signal "L13GND")
		(2 "B.Cu" signal "BOTTOM")
		(9 "F.Adhes" user "F.Adhesive")
		(11 "B.Adhes" user "B.Adhesive")
		(13 "F.Paste" user "Package Geometry/Pastemask Top")
		(15 "B.Paste" user "Package Geometry/Pastemask Bottom")
		(5 "F.SilkS" user "Ref Des/Silkscreen Top")
		(7 "B.SilkS" user "Ref Des/Silkscreen Bottom")
		(1 "F.Mask" user "Board Geometry/Soldermask Top")
		(3 "B.Mask" user "Board Geometry/Soldermask Bottom")
		(17 "Dwgs.User" user "User.Drawings")
		(19 "Cmts.User" user "User.Comments")
		(21 "Eco1.User" user "User.Eco1")
		(23 "Eco2.User" user "User.Eco2")
		(25 "Edge.Cuts" user "Board Geometry/Outline")
		(27 "Margin" user)
		(31 "F.CrtYd" user "Package Geometry/Place Bound Top")
		(29 "B.CrtYd" user "Package Geometry/Place Bound Bottom")
		(35 "F.Fab" user "Ref Des/Assembly Top")
		(33 "B.Fab" user "Ref Des/Assembly Bottom")
	)
	(footprint ""
		(layer "B.Cu")
		(at 350.3168 -153.8732 180)
		(property "Reference" "CT43"
			(at 0.8382 -0.84963 180)
			(unlocked yes)
			(layer "B.SilkS")
			(effects
				(font
					(size 0.7874 0.5842)
					(thickness 0.1524)
				)
				(justify left mirror)
			)
		)
		(property "Value" ""
			(at 0 0 0)
			(layer "B.Fab")
			(effects
				(font
					(size 1.27 1.27)
				)
				(justify mirror)
			)
		)
		(duplicate_pad_numbers_are_jumpers no)
		(fp_poly
			(pts
				(xy -0.3048 -0.1016) (xy -0.3048 0.9906) (xy 0.3048 0.9906) (xy 0.3048 -0.1016)
			)
			(stroke
				(width 0)
				(type default)
			)
			(fill no)
			(layer "B.CrtYd")
		)
		(fp_line
			(start 0.3048 0.9906)
			(end -0.3048 0.9906)
			(stroke
				(width 0.1)
				(type default)
			)
			(layer "B.Fab")
		)
		(fp_line
			(start 0.3048 -0.1016)
			(end 0.3048 0.9906)
			(stroke
				(width 0.1)
				(type default)
			)
			(layer "B.Fab")
		)
		(fp_line
			(start -0.3048 0.9906)
			(end -0.3048 -0.1016)
			(stroke
				(width 0.1)
				(type default)
			)
			(layer "B.Fab")
		)
		(fp_line
			(start -0.3048 -0.1016)
			(end 0.3048 -0.1016)
			(stroke
				(width 0.1)
				(type default)
			)
			(layer "B.Fab")
		)
		(pad "1" smd rect
			(at 0 0)
			(size 0.508 0.508)
			(layers "B.Cu" "B.Mask" "B.Paste")
			(net "A_TSENSE_PVDDQ_DEF")
		)
		(pad "2" smd rect
			(at 0 0.889)
			(size 0.508 0.508)
			(layers "B.Cu" "B.Mask" "B.Paste")
			(net "GND")
		)
		(zone
			(layer "B.Cu")
			(hatch none 0.5)
			(connect_pads
				(clearance 0)
			)
			(min_thickness 0.25)
			(keepout
				(tracks not_allowed)
				(vias allowed)
				(pads allowed)
				(copperpour not_allowed)
				(footprints allowed)
			)
			(placement
				(enabled no)
				(sheetname "")
			)
			(fill
				(thermal_gap 0.5)
				(thermal_bridge_width 0.5)
				(island_removal_mode 0)
			)
			(polygon
				(pts
					(xy 350.0628 -154.5082) (xy 350.5708 -154.5082) (xy 350.5708 -154.1272) (xy 350.0628 -154.1272)
				)
			)
		)
		(zone
			(layer "B.Cu")
			(hatch none 0.5)
			(connect_pads
				(clearance 0)
			)
			(min_thickness 0.25)
			(keepout
				(tracks allowed)
				(vias not_allowed)
				(pads allowed)
				(copperpour not_allowed)
				(footprints allowed)
			)
			(placement
				(enabled no)
				(sheetname "")
			)
			(fill
				(thermal_gap 0.5)
				(thermal_bridge_width 0.5)
				(island_removal_mode 0)
			)
			(polygon
				(pts
					(xy 350.0628 -154.1272) (xy 350.5708 -154.1272) (xy 350.5708 -154.5082) (xy 350.0628 -154.5082)
				)
			)
		)
	)
	(footprint ""
		(layer "B.Cu")
		(at 344.678 -82.677 180)
		(property "Reference" "R3P25"
			(at 0 0 0)
			(layer "B.SilkS")
			(hide yes)
			(effects
				(font
					(size 1.27 1.27)
				)
				(justify mirror)
			)
		)
		(property "Value" ""
			(at 0 0 0)
			(layer "B.Fab")
			(effects
				(font
					(size 1.27 1.27)
				)
				(justify mirror)
			)
		)
		(duplicate_pad_numbers_are_jumpers no)
		(fp_poly
			(pts
				(xy 0.2794 -0.1016) (xy -0.2794 -0.1016) (xy -0.2794 0.9906) (xy 0.2794 0.9906)
			)
			(stroke
				(width 0)
				(type default)
			)
			(fill no)
			(layer "B.CrtYd")
		)
		(fp_line
			(start 0.2794 0.9906)
			(end -0.2794 0.9906)
			(stroke
				(width 0.1)
				(type default)
			)
			(layer "B.Fab")
		)
		(fp_line
			(start 0.2794 -0.1016)
			(end 0.2794 0.9906)
			(stroke
				(width 0.1)
				(type default)
			)
			(layer "B.Fab")
		)
		(fp_line
			(start -0.2794 0.9906)
			(end -0.2794 -0.1016)
			(stroke
				(width 0.1)
				(type default)
			)
			(layer "B.Fab")
		)
		(fp_line
			(start -0.2794 -0.1016)
			(end 0.2794 -0.1016)
			(stroke
				(width 0.1)
				(type default)
			)
			(layer "B.Fab")
		)
		(pad "1" smd rect
			(at 0 0)
			(size 0.508 0.508)
			(layers "B.Cu" "B.Mask" "B.Paste")
			(net "P3V3_STBY")
		)
		(pad "2" smd rect
			(at 0 0.889)
			(size 0.508 0.508)
			(layers "B.Cu" "B.Mask" "B.Paste")
			(net "PWRGD_PVCCIO_CPU0_R")
		)
		(zone
			(layer "B.Cu")
			(hatch none 0.5)
			(connect_pads
				(clearance 0)
			)
			(min_thickness 0.25)
			(keepout
				(tracks not_allowed)
				(vias allowed)
				(pads allowed)
				(copperpour not_allowed)
				(footprints allowed)
			)
			(placement
				(enabled no)
				(sheetname "")
			)
			(fill
				(thermal_gap 0.5)
				(thermal_bridge_width 0.5)
				(island_removal_mode 0)
			)
			(polygon
				(pts
					(xy 344.424 -83.312) (xy 344.932 -83.312) (xy 344.932 -82.931) (xy 344.424 -82.931)
				)
			)
		)
		(zone
			(layer "B.Cu")
			(hatch none 0.5)
			(connect_pads
				(clearance 0)
			)
			(min_thickness 0.25)
			(keepout
				(tracks allowed)
				(vias not_allowed)
				(pads allowed)
				(copperpour not_allowed)
				(footprints allowed)
			)
			(placement
				(enabled no)
				(sheetname "")
			)
			(fill
				(thermal_gap 0.5)
				(thermal_bridge_width 0.5)
				(island_removal_mode 0)
			)
			(polygon
				(pts
					(xy 344.424 -82.931) (xy 344.932 -82.931) (xy 344.932 -83.312) (xy 344.424 -83.312)
				)
			)
		)
	)
	(footprint ""
		(layer "B.Cu")
		(at 276.479 -68.58 90)
		(property "Reference" "R4P17"
			(at 0 0 90)
			(layer "B.SilkS")
			(hide yes)
			(effects
				(font
					(size 1.27 1.27)
				)
				(justify mirror)
			)
		)
		(property "Value" ""
			(at 0 0 90)
			(layer "B.Fab")
			(effects
				(font
					(size 1.27 1.27)
				)
				(justify mirror)
			)
		)
		(duplicate_pad_numbers_are_jumpers no)
		(fp_poly
			(pts
				(xy 0.2794 -0.1016) (xy -0.2794 -0.1016) (xy -0.2794 0.9906) (xy 0.2794 0.9906)
			)
			(stroke
				(width 0)
				(type default)
			)
			(fill no)
			(layer "B.CrtYd")
		)
		(fp_line
			(start 0.2794 -0.1016)
			(end 0.2794 0.9906)
			(stroke
				(width 0.1)
				(type default)
			)
			(layer "B.Fab")
		)
		(fp_line
			(start -0.2794 -0.1016)
			(end 0.2794 -0.1016)
			(stroke
				(width 0.1)
				(type default)
			)
			(layer "B.Fab")
		)
		(fp_line
			(start 0.2794 0.9906)
			(end -0.2794 0.9906)
			(stroke
				(width 0.1)
				(type default)
			)
			(layer "B.Fab")
		)
		(fp_line
			(start -0.2794 0.9906)
			(end -0.2794 -0.1016)
			(stroke
				(width 0.1)
				(type default)
			)
			(layer "B.Fab")
		)
		(pad "1" smd rect
			(at 0 0 270)
			(size 0.508 0.508)
			(layers "B.Cu" "B.Mask" "B.Paste")
			(net "H_CPU0_MEMABC_MEMHOT_G_N")
		)
		(pad "2" smd rect
			(at 0 0.889 270)
			(size 0.508 0.508)
			(layers "B.Cu" "B.Mask" "B.Paste")
			(net "PVCCIO_CPU0")
		)
		(zone
			(layer "B.Cu")
			(hatch none 0.5)
			(connect_pads
				(clearance 0)
			)
			(min_thickness 0.25)
			(keepout
				(tracks allowed)
				(vias not_allowed)
				(pads allowed)
				(copperpour not_allowed)
				(footprints allowed)
			)
			(placement
				(enabled no)
				(sheetname "")
			)
			(fill
				(thermal_gap 0.5)
				(thermal_bridge_width 0.5)
				(island_removal_mode 0)
			)
			(polygon
				(pts
					(xy 276.733 -68.834) (xy 276.733 -68.326) (xy 277.114 -68.326) (xy 277.114 -68.834)
				)
			)
		)
		(zone
			(layer "B.Cu")
			(hatch none 0.5)
			(connect_pads
				(clearance 0)
			)
			(min_thickness 0.25)
			(keepout
				(tracks not_allowed)
				(vias allowed)
				(pads allowed)
				(copperpour not_allowed)
				(footprints allowed)
			)
			(placement
				(enabled no)
				(sheetname "")
			)
			(fill
				(thermal_gap 0.5)
				(thermal_bridge_width 0.5)
				(island_removal_mode 0)
			)
			(polygon
				(pts
					(xy 277.114 -68.834) (xy 277.114 -68.326) (xy 276.733 -68.326) (xy 276.733 -68.834)
				)
			)
		)
	)
)
